#ISCELL
  pure_quanta quanta_title_block_c *
  *
#ISCELL
  standard offpage *
  page191_i1
#ISCELL
  standard offpage *
  page191_i10
#CELL
  pure_quanta q_res *
  page191_i14
#CELL
  pure_quanta q_res *
  page191_i2
#ISCELL
  standard offpage *
  page191_i22
#ISCELL
  standard offpage *
  page191_i28
#CELL
  pure_quanta q_res *
  page191_i29
#ISCELL
  standard offpage *
  page191_i30
#ISCELL
  logical_power universal_power *
  page191_i34
#CELL
  pure_quanta q_res *
  page191_i35
#ISCELL
  logical_power universal_power *
  page191_i37
#CELL
  pure_quanta q_res *
  page191_i38
#ISCELL
  standard offpage *
  page191_i6
